(kicad_pcb
	(version 20260206)
	(generator "pcbnew")
	(generator_version "10.0")
	(general
		(thickness 1.6)
		(legacy_teardrops no)
	)
	(paper "A4")
	(title_block
		(title "01162023_DA0F0TEBIF0_F0T_Expander_BD_F_brd_V02_OCP.brd")
		(comment 1 "Grand Teton / footprints 3513-3519 of 9728")
	)
	(layers
		(0 "F.Cu" signal "TOP")
		(4 "In1.Cu" signal "GND")
		(6 "In2.Cu" signal "VCC")
		(8 "In3.Cu" signal "VCC1")
		(10 "In4.Cu" signal "GND1")
		(12 "In5.Cu" signal "IN1")
		(14 "In6.Cu" signal "GND2")
		(16 "In7.Cu" signal "IN2")
		(18 "In8.Cu" signal "GND3")
		(20 "In9.Cu" signal "IN3")
		(22 "In10.Cu" signal "GND4")
		(24 "In11.Cu" signal "IN4")
		(26 "In12.Cu" signal "GND5")
		(28 "In13.Cu" signal "IN5")
		(30 "In14.Cu" signal "GND6")
		(32 "In15.Cu" signal "IN6")
		(34 "In16.Cu" signal "GND7")
		(2 "B.Cu" signal "BOTTOM")
		(9 "F.Adhes" user "F.Adhesive")
		(11 "B.Adhes" user "B.Adhesive")
		(13 "F.Paste" user "Package Geometry/Pastemask Top")
		(15 "B.Paste" user "Package Geometry/Pastemask Bottom")
		(5 "F.SilkS" user "Ref Des/Silkscreen Top")
		(7 "B.SilkS" user "Ref Des/Silkscreen Bottom")
		(1 "F.Mask" user "Board Geometry/Soldermask Top")
		(3 "B.Mask" user "Board Geometry/Soldermask Bottom")
		(17 "Dwgs.User" user "User.Drawings")
		(19 "Cmts.User" user "User.Comments")
		(21 "Eco1.User" user "User.Eco1")
		(23 "Eco2.User" user "User.Eco2")
		(25 "Edge.Cuts" user "Board Geometry/Outline")
		(27 "Margin" user)
		(31 "F.CrtYd" user "Package Geometry/Place Bound Top")
		(29 "B.CrtYd" user "Package Geometry/Place Bound Bottom")
		(35 "F.Fab" user "Ref Des/Assembly Top")
		(33 "B.Fab" user "Ref Des/Assembly Bottom")
	)
	(footprint ""
		(layer "F.Cu")
		(at 214.307674 -365.978186 180)
		(property "Reference" "PR32"
			(at 0 0 180)
			(layer "F.SilkS")
			(hide yes)
			(effects
				(font
					(size 1.27 1.27)
				)
			)
		)
		(property "Value" ""
			(at 0 0 180)
			(layer "F.Fab")
			(effects
				(font
					(size 1.27 1.27)
				)
			)
		)
		(duplicate_pad_numbers_are_jumpers no)
		(fp_line
			(start 0.7874 0.4064)
			(end -0.7874 0.4064)
			(stroke
				(width 0.1524)
				(type default)
			)
			(layer "F.SilkS")
		)
		(fp_line
			(start 0.7874 -0.4064)
			(end 0.7874 0.4064)
			(stroke
				(width 0.1524)
				(type default)
			)
			(layer "F.SilkS")
		)
		(fp_line
			(start -0.7874 0.4064)
			(end -0.7874 -0.4064)
			(stroke
				(width 0.1524)
				(type default)
			)
			(layer "F.SilkS")
		)
		(fp_line
			(start -0.7874 -0.4064)
			(end 0.7874 -0.4064)
			(stroke
				(width 0.1524)
				(type default)
			)
			(layer "F.SilkS")
		)
		(fp_line
			(start 0.67945 0.3048)
			(end 0.120396 0.3048)
			(stroke
				(width 0.1)
				(type default)
			)
			(layer "F.Fab")
		)
		(fp_line
			(start 0.67945 -0.3048)
			(end 0.67945 0.3048)
			(stroke
				(width 0.1)
				(type default)
			)
			(layer "F.Fab")
		)
		(fp_line
			(start 0.12065 -0.2794)
			(end 0.12065 -0.3048)
			(stroke
				(width 0.1)
				(type default)
			)
			(layer "F.Fab")
		)
		(fp_line
			(start 0.12065 -0.3048)
			(end 0.67945 -0.3048)
			(stroke
				(width 0.1)
				(type default)
			)
			(layer "F.Fab")
		)
		(fp_line
			(start 0.120396 0.3048)
			(end 0.120396 0.2794)
			(stroke
				(width 0.1)
				(type default)
			)
			(layer "F.Fab")
		)
		(fp_line
			(start 0.120396 0.2794)
			(end -0.12065 0.2794)
			(stroke
				(width 0.1)
				(type default)
			)
			(layer "F.Fab")
		)
		(fp_line
			(start -0.12065 0.3048)
			(end -0.67945 0.3048)
			(stroke
				(width 0.1)
				(type default)
			)
			(layer "F.Fab")
		)
		(fp_line
			(start -0.12065 0.2794)
			(end -0.12065 0.3048)
			(stroke
				(width 0.1)
				(type default)
			)
			(layer "F.Fab")
		)
		(fp_line
			(start -0.12065 -0.2794)
			(end 0.12065 -0.2794)
			(stroke
				(width 0.1)
				(type default)
			)
			(layer "F.Fab")
		)
		(fp_line
			(start -0.12065 -0.305054)
			(end -0.12065 -0.2794)
			(stroke
				(width 0.1)
				(type default)
			)
			(layer "F.Fab")
		)
		(fp_line
			(start -0.67945 0.3048)
			(end -0.67945 -0.305054)
			(stroke
				(width 0.1)
				(type default)
			)
			(layer "F.Fab")
		)
		(fp_line
			(start -0.67945 -0.305054)
			(end -0.12065 -0.305054)
			(stroke
				(width 0.1)
				(type default)
			)
			(layer "F.Fab")
		)
		(pad "1" smd circle
			(at -0.40005 0 180)
			(size 0 0)
			(layers "F.Cu" "F.Mask" "F.Paste")
			(net "HSC_OCREF")
		)
		(pad "2" smd circle
			(at 0.40005 0 180)
			(size 0 0)
			(layers "F.Cu" "F.Mask" "F.Paste")
			(net "AGND_HSC")
		)
	)
	(footprint ""
		(layer "F.Cu")
		(at 437.312308 -300.64202 -90)
		(property "Reference" "R3995"
			(at 0 0 270)
			(layer "F.SilkS")
			(hide yes)
			(effects
				(font
					(size 1.27 1.27)
				)
			)
		)
		(property "Value" ""
			(at 0 0 270)
			(layer "F.Fab")
			(effects
				(font
					(size 1.27 1.27)
				)
			)
		)
		(duplicate_pad_numbers_are_jumpers no)
		(fp_line
			(start -0.7874 0.4064)
			(end -0.7874 -0.4064)
			(stroke
				(width 0.1524)
				(type default)
			)
			(layer "F.SilkS")
		)
		(fp_line
			(start 0.7874 0.4064)
			(end -0.7874 0.4064)
			(stroke
				(width 0.1524)
				(type default)
			)
			(layer "F.SilkS")
		)
		(fp_line
			(start -0.7874 -0.4064)
			(end 0.7874 -0.4064)
			(stroke
				(width 0.1524)
				(type default)
			)
			(layer "F.SilkS")
		)
		(fp_line
			(start 0.7874 -0.4064)
			(end 0.7874 0.4064)
			(stroke
				(width 0.1524)
				(type default)
			)
			(layer "F.SilkS")
		)
		(fp_line
			(start -0.67945 0.3048)
			(end -0.67945 -0.305054)
			(stroke
				(width 0.1)
				(type default)
			)
			(layer "F.Fab")
		)
		(fp_line
			(start -0.12065 0.3048)
			(end -0.67945 0.3048)
			(stroke
				(width 0.1)
				(type default)
			)
			(layer "F.Fab")
		)
		(fp_line
			(start 0.120396 0.3048)
			(end 0.120396 0.2794)
			(stroke
				(width 0.1)
				(type default)
			)
			(layer "F.Fab")
		)
		(fp_line
			(start 0.67945 0.3048)
			(end 0.120396 0.3048)
			(stroke
				(width 0.1)
				(type default)
			)
			(layer "F.Fab")
		)
		(fp_line
			(start -0.12065 0.2794)
			(end -0.12065 0.3048)
			(stroke
				(width 0.1)
				(type default)
			)
			(layer "F.Fab")
		)
		(fp_line
			(start 0.120396 0.2794)
			(end -0.12065 0.2794)
			(stroke
				(width 0.1)
				(type default)
			)
			(layer "F.Fab")
		)
		(fp_line
			(start -0.12065 -0.2794)
			(end 0.12065 -0.2794)
			(stroke
				(width 0.1)
				(type default)
			)
			(layer "F.Fab")
		)
		(fp_line
			(start 0.12065 -0.2794)
			(end 0.12065 -0.3048)
			(stroke
				(width 0.1)
				(type default)
			)
			(layer "F.Fab")
		)
		(fp_line
			(start 0.12065 -0.3048)
			(end 0.67945 -0.3048)
			(stroke
				(width 0.1)
				(type default)
			)
			(layer "F.Fab")
		)
		(fp_line
			(start 0.67945 -0.3048)
			(end 0.67945 0.3048)
			(stroke
				(width 0.1)
				(type default)
			)
			(layer "F.Fab")
		)
		(fp_line
			(start -0.67945 -0.305054)
			(end -0.12065 -0.305054)
			(stroke
				(width 0.1)
				(type default)
			)
			(layer "F.Fab")
		)
		(fp_line
			(start -0.12065 -0.305054)
			(end -0.12065 -0.2794)
			(stroke
				(width 0.1)
				(type default)
			)
			(layer "F.Fab")
		)
		(pad "1" smd circle
			(at -0.40005 0 270)
			(size 0 0)
			(layers "F.Cu" "F.Mask" "F.Paste")
			(net "I2C0_PEX3_SHPC_SDA")
		)
		(pad "2" smd circle
			(at 0.40005 0 270)
			(size 0 0)
			(layers "F.Cu" "F.Mask" "F.Paste")
			(net "I2C_PEX3_HOST_SDA")
		)
	)
	(footprint ""
		(layer "F.Cu")
		(at 195.226178 -39.73576 -90)
		(property "Reference" "R5560"
			(at 0 0 270)
			(layer "F.SilkS")
			(hide yes)
			(effects
				(font
					(size 1.27 1.27)
				)
			)
		)
		(property "Value" ""
			(at 0 0 270)
			(layer "F.Fab")
			(effects
				(font
					(size 1.27 1.27)
				)
			)
		)
		(duplicate_pad_numbers_are_jumpers no)
		(fp_line
			(start -0.7874 0.4064)
			(end -0.7874 -0.4064)
			(stroke
				(width 0.1524)
				(type default)
			)
			(layer "F.SilkS")
		)
		(fp_line
			(start 0.7874 0.4064)
			(end -0.7874 0.4064)
			(stroke
				(width 0.1524)
				(type default)
			)
			(layer "F.SilkS")
		)
		(fp_line
			(start -0.7874 -0.4064)
			(end 0.7874 -0.4064)
			(stroke
				(width 0.1524)
				(type default)
			)
			(layer "F.SilkS")
		)
		(fp_line
			(start 0.7874 -0.4064)
			(end 0.7874 0.4064)
			(stroke
				(width 0.1524)
				(type default)
			)
			(layer "F.SilkS")
		)
		(fp_line
			(start -0.67945 0.3048)
			(end -0.67945 -0.305054)
			(stroke
				(width 0.1)
				(type default)
			)
			(layer "F.Fab")
		)
		(fp_line
			(start -0.12065 0.3048)
			(end -0.67945 0.3048)
			(stroke
				(width 0.1)
				(type default)
			)
			(layer "F.Fab")
		)
		(fp_line
			(start 0.120396 0.3048)
			(end 0.120396 0.2794)
			(stroke
				(width 0.1)
				(type default)
			)
			(layer "F.Fab")
		)
		(fp_line
			(start 0.67945 0.3048)
			(end 0.120396 0.3048)
			(stroke
				(width 0.1)
				(type default)
			)
			(layer "F.Fab")
		)
		(fp_line
			(start -0.12065 0.2794)
			(end -0.12065 0.3048)
			(stroke
				(width 0.1)
				(type default)
			)
			(layer "F.Fab")
		)
		(fp_line
			(start 0.120396 0.2794)
			(end -0.12065 0.2794)
			(stroke
				(width 0.1)
				(type default)
			)
			(layer "F.Fab")
		)
		(fp_line
			(start -0.12065 -0.2794)
			(end 0.12065 -0.2794)
			(stroke
				(width 0.1)
				(type default)
			)
			(layer "F.Fab")
		)
		(fp_line
			(start 0.12065 -0.2794)
			(end 0.12065 -0.3048)
			(stroke
				(width 0.1)
				(type default)
			)
			(layer "F.Fab")
		)
		(fp_line
			(start 0.12065 -0.3048)
			(end 0.67945 -0.3048)
			(stroke
				(width 0.1)
				(type default)
			)
			(layer "F.Fab")
		)
		(fp_line
			(start 0.67945 -0.3048)
			(end 0.67945 0.3048)
			(stroke
				(width 0.1)
				(type default)
			)
			(layer "F.Fab")
		)
		(fp_line
			(start -0.67945 -0.305054)
			(end -0.12065 -0.305054)
			(stroke
				(width 0.1)
				(type default)
			)
			(layer "F.Fab")
		)
		(fp_line
			(start -0.12065 -0.305054)
			(end -0.12065 -0.2794)
			(stroke
				(width 0.1)
				(type default)
			)
			(layer "F.Fab")
		)
		(pad "1" smd circle
			(at -0.40005 0 270)
			(size 0 0)
			(layers "F.Cu" "F.Mask" "F.Paste")
			(net "P3V3_AUX")
		)
		(pad "2" smd circle
			(at 0.40005 0 270)
			(size 0 0)
			(layers "F.Cu" "F.Mask" "F.Paste")
			(net "SSD7_AUX_P3V3_EN")
		)
	)
	(footprint ""
		(layer "F.Cu")
		(at 3.88366 -66.567812 180)
		(property "Reference" "R5870"
			(at 0 0 180)
			(layer "F.SilkS")
			(hide yes)
			(effects
				(font
					(size 1.27 1.27)
				)
			)
		)
		(property "Value" ""
			(at 0 0 180)
			(layer "F.Fab")
			(effects
				(font
					(size 1.27 1.27)
				)
			)
		)
		(duplicate_pad_numbers_are_jumpers no)
		(fp_line
			(start 0.7874 0.4064)
			(end -0.7874 0.4064)
			(stroke
				(width 0.1524)
				(type default)
			)
			(layer "F.SilkS")
		)
		(fp_line
			(start 0.7874 -0.4064)
			(end 0.7874 0.4064)
			(stroke
				(width 0.1524)
				(type default)
			)
			(layer "F.SilkS")
		)
		(fp_line
			(start -0.7874 0.4064)
			(end -0.7874 -0.4064)
			(stroke
				(width 0.1524)
				(type default)
			)
			(layer "F.SilkS")
		)
		(fp_line
			(start -0.7874 -0.4064)
			(end 0.7874 -0.4064)
			(stroke
				(width 0.1524)
				(type default)
			)
			(layer "F.SilkS")
		)
		(fp_line
			(start 0.67945 0.3048)
			(end 0.120396 0.3048)
			(stroke
				(width 0.1)
				(type default)
			)
			(layer "F.Fab")
		)
		(fp_line
			(start 0.67945 -0.3048)
			(end 0.67945 0.3048)
			(stroke
				(width 0.1)
				(type default)
			)
			(layer "F.Fab")
		)
		(fp_line
			(start 0.12065 -0.2794)
			(end 0.12065 -0.3048)
			(stroke
				(width 0.1)
				(type default)
			)
			(layer "F.Fab")
		)
		(fp_line
			(start 0.12065 -0.3048)
			(end 0.67945 -0.3048)
			(stroke
				(width 0.1)
				(type default)
			)
			(layer "F.Fab")
		)
		(fp_line
			(start 0.120396 0.3048)
			(end 0.120396 0.2794)
			(stroke
				(width 0.1)
				(type default)
			)
			(layer "F.Fab")
		)
		(fp_line
			(start 0.120396 0.2794)
			(end -0.12065 0.2794)
			(stroke
				(width 0.1)
				(type default)
			)
			(layer "F.Fab")
		)
		(fp_line
			(start -0.12065 0.3048)
			(end -0.67945 0.3048)
			(stroke
				(width 0.1)
				(type default)
			)
			(layer "F.Fab")
		)
		(fp_line
			(start -0.12065 0.2794)
			(end -0.12065 0.3048)
			(stroke
				(width 0.1)
				(type default)
			)
			(layer "F.Fab")
		)
		(fp_line
			(start -0.12065 -0.2794)
			(end 0.12065 -0.2794)
			(stroke
				(width 0.1)
				(type default)
			)
			(layer "F.Fab")
		)
		(fp_line
			(start -0.12065 -0.305054)
			(end -0.12065 -0.2794)
			(stroke
				(width 0.1)
				(type default)
			)
			(layer "F.Fab")
		)
		(fp_line
			(start -0.67945 0.3048)
			(end -0.67945 -0.305054)
			(stroke
				(width 0.1)
				(type default)
			)
			(layer "F.Fab")
		)
		(fp_line
			(start -0.67945 -0.305054)
			(end -0.12065 -0.305054)
			(stroke
				(width 0.1)
				(type default)
			)
			(layer "F.Fab")
		)
		(pad "1" smd circle
			(at -0.40005 0 180)
			(size 0 0)
			(layers "F.Cu" "F.Mask" "F.Paste")
			(net "PWRGD_P3V3_SSD0_D")
		)
		(pad "2" smd circle
			(at 0.40005 0 180)
			(size 0 0)
			(layers "F.Cu" "F.Mask" "F.Paste")
			(net "PWRGD_P3V3_SSD0_R")
		)
	)
	(footprint ""
		(layer "F.Cu")
		(at 71.526654 -55.418228 90)
		(property "Reference" "PC380"
			(at 0 0 90)
			(layer "F.SilkS")
			(hide yes)
			(effects
				(font
					(size 1.27 1.27)
				)
			)
		)
		(property "Value" ""
			(at 0 0 90)
			(layer "F.Fab")
			(effects
				(font
					(size 1.27 1.27)
				)
			)
		)
		(duplicate_pad_numbers_are_jumpers no)
		(fp_line
			(start 0.7874 -0.4064)
			(end 0.7874 0.4064)
			(stroke
				(width 0.1524)
				(type default)
			)
			(layer "F.SilkS")
		)
		(fp_line
			(start -0.7874 -0.4064)
			(end 0.7874 -0.4064)
			(stroke
				(width 0.1524)
				(type default)
			)
			(layer "F.SilkS")
		)
		(fp_line
			(start 0.7874 0.4064)
			(end -0.7874 0.4064)
			(stroke
				(width 0.1524)
				(type default)
			)
			(layer "F.SilkS")
		)
		(fp_line
			(start -0.7874 0.4064)
			(end -0.7874 -0.4064)
			(stroke
				(width 0.1524)
				(type default)
			)
			(layer "F.SilkS")
		)
		(fp_line
			(start -0.12065 -0.305054)
			(end -0.12065 -0.2794)
			(stroke
				(width 0.1)
				(type default)
			)
			(layer "F.Fab")
		)
		(fp_line
			(start -0.67945 -0.305054)
			(end -0.12065 -0.305054)
			(stroke
				(width 0.1)
				(type default)
			)
			(layer "F.Fab")
		)
		(fp_line
			(start 0.67945 -0.3048)
			(end 0.67945 0.3048)
			(stroke
				(width 0.1)
				(type default)
			)
			(layer "F.Fab")
		)
		(fp_line
			(start 0.12065 -0.3048)
			(end 0.67945 -0.3048)
			(stroke
				(width 0.1)
				(type default)
			)
			(layer "F.Fab")
		)
		(fp_line
			(start 0.12065 -0.2794)
			(end 0.12065 -0.3048)
			(stroke
				(width 0.1)
				(type default)
			)
			(layer "F.Fab")
		)
		(fp_line
			(start -0.12065 -0.2794)
			(end 0.12065 -0.2794)
			(stroke
				(width 0.1)
				(type default)
			)
			(layer "F.Fab")
		)
		(fp_line
			(start 0.120396 0.2794)
			(end -0.12065 0.2794)
			(stroke
				(width 0.1)
				(type default)
			)
			(layer "F.Fab")
		)
		(fp_line
			(start -0.12065 0.2794)
			(end -0.12065 0.3048)
			(stroke
				(width 0.1)
				(type default)
			)
			(layer "F.Fab")
		)
		(fp_line
			(start 0.67945 0.3048)
			(end 0.120396 0.3048)
			(stroke
				(width 0.1)
				(type default)
			)
			(layer "F.Fab")
		)
		(fp_line
			(start 0.120396 0.3048)
			(end 0.120396 0.2794)
			(stroke
				(width 0.1)
				(type default)
			)
			(layer "F.Fab")
		)
		(fp_line
			(start -0.12065 0.3048)
			(end -0.67945 0.3048)
			(stroke
				(width 0.1)
				(type default)
			)
			(layer "F.Fab")
		)
		(fp_line
			(start -0.67945 0.3048)
			(end -0.67945 -0.305054)
			(stroke
				(width 0.1)
				(type default)
			)
			(layer "F.Fab")
		)
		(pad "1" smd circle
			(at -0.40005 0 90)
			(size 0 0)
			(layers "F.Cu" "F.Mask" "F.Paste")
			(net "P12V_SSD2_R")
		)
		(pad "2" smd circle
			(at 0.40005 0 90)
			(size 0 0)
			(layers "F.Cu" "F.Mask" "F.Paste")
			(net "GND")
		)
	)
	(footprint ""
		(layer "F.Cu")
		(at 198.76135 -120.476772 180)
		(property "Reference" "C241"
			(at 0 0 180)
			(layer "F.SilkS")
			(hide yes)
			(effects
				(font
					(size 1.27 1.27)
				)
			)
		)
		(property "Value" ""
			(at 0 0 180)
			(layer "F.Fab")
			(effects
				(font
					(size 1.27 1.27)
				)
			)
		)
		(duplicate_pad_numbers_are_jumpers no)
		(fp_line
			(start 0.299974 0.150114)
			(end -0.299974 0.150114)
			(stroke
				(width 0.1)
				(type default)
			)
			(layer "F.Fab")
		)
		(fp_line
			(start 0.299974 -0.150114)
			(end 0.299974 0.150114)
			(stroke
				(width 0.1)
				(type default)
			)
			(layer "F.Fab")
		)
		(fp_line
			(start -0.299974 0.150114)
			(end -0.299974 -0.150114)
			(stroke
				(width 0.1)
				(type default)
			)
			(layer "F.Fab")
		)
		(fp_line
			(start -0.299974 -0.150114)
			(end 0.299974 -0.150114)
			(stroke
				(width 0.1)
				(type default)
			)
			(layer "F.Fab")
		)
		(pad "1" smd rect
			(at -0.2667 0 180)
			(size 0.3048 0.381)
			(layers "F.Cu" "F.Mask" "F.Paste")
			(net "P5E_PEX1_STN0_TX_DN<1>")
		)
		(pad "2" smd rect
			(at 0.2667 0 180)
			(size 0.3048 0.381)
			(layers "F.Cu" "F.Mask" "F.Paste")
			(net "P5E_PEX1_STN0_TX_C_DN<1>")
		)
	)
	(footprint ""
		(layer "F.Cu")
		(at 220.34373 -47.92091)
		(property "Reference" "R581"
			(at 0 0 0)
			(layer "F.SilkS")
			(hide yes)
			(effects
				(font
					(size 1.27 1.27)
				)
			)
		)
		(property "Value" ""
			(at 0 0 0)
			(layer "F.Fab")
			(effects
				(font
					(size 1.27 1.27)
				)
			)
		)
		(duplicate_pad_numbers_are_jumpers no)
		(fp_line
			(start -0.7874 -0.4064)
			(end 0.7874 -0.4064)
			(stroke
				(width 0.1524)
				(type default)
			)
			(layer "F.SilkS")
		)
		(fp_line
			(start -0.7874 0.4064)
			(end -0.7874 -0.4064)
			(stroke
				(width 0.1524)
				(type default)
			)
			(layer "F.SilkS")
		)
		(fp_line
			(start 0.7874 -0.4064)
			(end 0.7874 0.4064)
			(stroke
				(width 0.1524)
				(type default)
			)
			(layer "F.SilkS")
		)
		(fp_line
			(start 0.7874 0.4064)
			(end -0.7874 0.4064)
			(stroke
				(width 0.1524)
				(type default)
			)
			(layer "F.SilkS")
		)
		(fp_line
			(start -0.67945 -0.305054)
			(end -0.12065 -0.305054)
			(stroke
				(width 0.1)
				(type default)
			)
			(layer "F.Fab")
		)
		(fp_line
			(start -0.67945 0.3048)
			(end -0.67945 -0.305054)
			(stroke
				(width 0.1)
				(type default)
			)
			(layer "F.Fab")
		)
		(fp_line
			(start -0.12065 -0.305054)
			(end -0.12065 -0.2794)
			(stroke
				(width 0.1)
				(type default)
			)
			(layer "F.Fab")
		)
		(fp_line
			(start -0.12065 -0.2794)
			(end 0.12065 -0.2794)
			(stroke
				(width 0.1)
				(type default)
			)
			(layer "F.Fab")
		)
		(fp_line
			(start -0.12065 0.2794)
			(end -0.12065 0.3048)
			(stroke
				(width 0.1)
				(type default)
			)
			(layer "F.Fab")
		)
		(fp_line
			(start -0.12065 0.3048)
			(end -0.67945 0.3048)
			(stroke
				(width 0.1)
				(type default)
			)
			(layer "F.Fab")
		)
		(fp_line
			(start 0.120396 0.2794)
			(end -0.12065 0.2794)
			(stroke
				(width 0.1)
				(type default)
			)
			(layer "F.Fab")
		)
		(fp_line
			(start 0.120396 0.3048)
			(end 0.120396 0.2794)
			(stroke
				(width 0.1)
				(type default)
			)
			(layer "F.Fab")
		)
		(fp_line
			(start 0.12065 -0.3048)
			(end 0.67945 -0.3048)
			(stroke
				(width 0.1)
				(type default)
			)
			(layer "F.Fab")
		)
		(fp_line
			(start 0.12065 -0.2794)
			(end 0.12065 -0.3048)
			(stroke
				(width 0.1)
				(type default)
			)
			(layer "F.Fab")
		)
		(fp_line
			(start 0.67945 -0.3048)
			(end 0.67945 0.3048)
			(stroke
				(width 0.1)
				(type default)
			)
			(layer "F.Fab")
		)
		(fp_line
			(start 0.67945 0.3048)
			(end 0.120396 0.3048)
			(stroke
				(width 0.1)
				(type default)
			)
			(layer "F.Fab")
		)
		(pad "1" smd circle
			(at -0.40005 0)
			(size 0 0)
			(layers "F.Cu" "F.Mask" "F.Paste")
			(net "P3V3_AUX")
		)
		(pad "2" smd circle
			(at 0.40005 0)
			(size 0 0)
			(layers "F.Cu" "F.Mask" "F.Paste")
			(net "SSD_0_7_ADC_ALERT_N")
		)
	)
)
